# T6G (Grand Teton) — schematic netlist excerpt (pin names and nets, part order shuffled) for the footprints in the layout excerpt that follows; sources: Cadence DE-HDL packaged netlist, KiCad conversion of 04192023_DAF0TMB3IC0_F0TG_MB_C_brd_V02_OCP.brd

U10  9ZXL0451EKILFT  IC  pkg VFQFPN32_TH_0-5_5X5XD  page 183
  \^ckpwrgd_pd#\  = FM_9ZXL045_P1_DEV_EN
  VDDR  = P3V3_9ZXL045_P1_VDDR
  DIF_IN  = CLK_100M_CPU1_CLK13_DP
  \dif_in#\  = CLK_100M_CPU1_CLK13_DN
  VSADR0_TRI  = CLK_9ZXL045_P1_SADR0
  SMBDAT  = SMB_9ZXL045_P1_SDA
  SMBCLK  = SMB_9ZXL045_P1_SCL
  \fbout_nc#\  = NC_U10_FBOUT_N
  FBOUT_NC  = NC_U10_FBOUT
  NC0  = NC_U10_NC0
  NC1  = NC_U10_NC1
  VDD0  = P3V3_9ZXL045_P1_VDD
  DIF0  = CLK_100M_RETIMER_CPU1_P0_R_DP
  \dif0#\  = CLK_100M_RETIMER_CPU1_P0_R_DN
  \voe0#\  = FM_9ZXL045_P1_0_OE_N
  VDD1  = P3V3_9ZXL045_P1_VDD
  NC2  = NC_U10_NC2
  \voe1#\  = FM_9ZXL045_P1_1_OE_N
  DIF1  = CLK_100M_RETIMER_CPU1_P1_R_DP
  \dif1#\  = CLK_100M_RETIMER_CPU1_P1_R_DN
  VDD2  = P3V3_9ZXL045_P1_VDD
  DIF2  = CLK_100M_RETIMER_CPU1_P2_R_DP
  \dif2#\  = CLK_100M_RETIMER_CPU1_P2_R_DN
  \voe2#\  = FM_9ZXL045_P1_2_OE_N
  VDD3  = P3V3_9ZXL045_P1_VDD
  \voe3#\  = FM_9ZXL045_P1_3_OE_N
  DIF3  = CLK_100M_RETIMER_CPU1_P3_R_DP
  \dif3#\  = CLK_100M_RETIMER_CPU1_P3_R_DN
  VDD4  = P3V3_9ZXL045_P1_VDD
  NC3  = NC_U10_NC3
  VDDA  = P3V3_9ZXL045_P1_VDDA
  \^hibw_bypm_lobw#\  = CLK_9ZXL045_P1_HIBW
  EPAD_GND  = GND

(kicad_pcb
	(version 20260206)
	(generator "pcbnew")
	(generator_version "10.0")
	(general
		(thickness 1.6)
		(legacy_teardrops no)
	)
	(paper "A4")
	(title_block
		(title "04192023_DAF0TMB3IC0_F0TG_MB_C_brd_V02_OCP.brd")
		(comment 1 "Grand Teton / footprint 4405 of 8354 (U10), pads 1-33 of 33")
	)
	(layers
		(0 "F.Cu" signal "TOP")
		(4 "In1.Cu" signal "GND")
		(6 "In2.Cu" signal "IN1")
		(8 "In3.Cu" signal "GND1")
		(10 "In4.Cu" signal "IN2")
		(12 "In5.Cu" signal "GND2")
		(14 "In6.Cu" signal "IN3")
		(16 "In7.Cu" signal "GND3")
		(18 "In8.Cu" signal "VCC")
		(20 "In9.Cu" signal "VCC1")
		(22 "In10.Cu" signal "GND4")
		(24 "In11.Cu" signal "IN4")
		(26 "In12.Cu" signal "GND5")
		(28 "In13.Cu" signal "IN5")
		(30 "In14.Cu" signal "GND6")
		(32 "In15.Cu" signal "IN6")
		(34 "In16.Cu" signal "GND7")
		(2 "B.Cu" signal "BOTTOM")
		(9 "F.Adhes" user "F.Adhesive")
		(11 "B.Adhes" user "B.Adhesive")
		(13 "F.Paste" user "Package Geometry/Pastemask Top")
		(15 "B.Paste" user "Package Geometry/Pastemask Bottom")
		(5 "F.SilkS" user "Ref Des/Silkscreen Top")
		(7 "B.SilkS" user "Ref Des/Silkscreen Bottom")
		(1 "F.Mask" user "Board Geometry/Soldermask Top")
		(3 "B.Mask" user "Board Geometry/Soldermask Bottom")
		(17 "Dwgs.User" user "User.Drawings")
		(19 "Cmts.User" user "User.Comments")
		(21 "Eco1.User" user "User.Eco1")
		(23 "Eco2.User" user "User.Eco2")
		(25 "Edge.Cuts" user "Board Geometry/Outline")
		(27 "Margin" user)
		(31 "F.CrtYd" user "Package Geometry/Place Bound Top")
		(29 "B.CrtYd" user "Package Geometry/Place Bound Bottom")
		(35 "F.Fab" user "Ref Des/Assembly Top")
		(33 "B.Fab" user "Ref Des/Assembly Bottom")
	)
	(footprint ""
		(layer "F.Cu")
		(at 106.246422 -409.63215 -90)
		(property "Reference" "U10"
			(at -0.080772 -3.860546 90)
			(unlocked yes)
			(layer "F.SilkS")
			(effects
				(font
					(size 0.7874 0.5842)
					(thickness 0.1524)
				)
			)
		)
		(property "Value" ""
			(at 0 0 270)
			(layer "F.Fab")
			(effects
				(font
					(size 1.27 1.27)
				)
			)
		)
		(duplicate_pad_numbers_are_jumpers no)
		(pad "1" smd rect
			(at -2.3749 -1.75006 180)
			(size 0.254 0.5588)
			(layers "F.Cu" "F.Mask" "F.Paste")
			(net "FM_9ZXL045_P1_DEV_EN")
		)
		(pad "2" smd rect
			(at -2.3749 -1.249934 180)
			(size 0.254 0.5588)
			(layers "F.Cu" "F.Mask" "F.Paste")
			(net "P3V3_9ZXL045_P1_VDDR")
		)
		(pad "3" smd rect
			(at -2.3749 -0.750062 180)
			(size 0.254 0.5588)
			(layers "F.Cu" "F.Mask" "F.Paste")
			(net "CLK_100M_CPU1_CLK13_DP")
		)
		(pad "4" smd rect
			(at -2.3749 -0.249936 180)
			(size 0.254 0.5588)
			(layers "F.Cu" "F.Mask" "F.Paste")
			(net "CLK_100M_CPU1_CLK13_DN")
		)
		(pad "5" smd rect
			(at -2.3749 0.249936 180)
			(size 0.254 0.5588)
			(layers "F.Cu" "F.Mask" "F.Paste")
			(net "CLK_9ZXL045_P1_SADR0")
		)
		(pad "6" smd rect
			(at -2.3749 0.750062 180)
			(size 0.254 0.5588)
			(layers "F.Cu" "F.Mask" "F.Paste")
			(net "SMB_9ZXL045_P1_SDA")
		)
		(pad "7" smd rect
			(at -2.3749 1.249934 180)
			(size 0.254 0.5588)
			(layers "F.Cu" "F.Mask" "F.Paste")
			(net "SMB_9ZXL045_P1_SCL")
		)
		(pad "8" smd rect
			(at -2.3749 1.75006 180)
			(size 0.254 0.5588)
			(layers "F.Cu" "F.Mask" "F.Paste")
			(net "NC_U10_FBOUT_N")
		)
		(pad "9" smd rect
			(at -1.75006 2.3749 270)
			(size 0.254 0.5588)
			(layers "F.Cu" "F.Mask" "F.Paste")
			(net "NC_U10_FBOUT")
		)
		(pad "10" smd rect
			(at -1.249934 2.3749 270)
			(size 0.254 0.5588)
			(layers "F.Cu" "F.Mask" "F.Paste")
			(net "NC_U10_NC0")
		)
		(pad "11" smd rect
			(at -0.750062 2.3749 270)
			(size 0.254 0.5588)
			(layers "F.Cu" "F.Mask" "F.Paste")
			(net "NC_U10_NC1")
		)
		(pad "12" smd rect
			(at -0.249936 2.3749 270)
			(size 0.254 0.5588)
			(layers "F.Cu" "F.Mask" "F.Paste")
			(net "P3V3_9ZXL045_P1_VDD")
		)
		(pad "13" smd rect
			(at 0.249936 2.3749 270)
			(size 0.254 0.5588)
			(layers "F.Cu" "F.Mask" "F.Paste")
			(net "CLK_100M_RETIMER_CPU1_P0_R_DP")
		)
		(pad "14" smd rect
			(at 0.750062 2.3749 270)
			(size 0.254 0.5588)
			(layers "F.Cu" "F.Mask" "F.Paste")
			(net "CLK_100M_RETIMER_CPU1_P0_R_DN")
		)
		(pad "15" smd rect
			(at 1.249934 2.3749 270)
			(size 0.254 0.5588)
			(layers "F.Cu" "F.Mask" "F.Paste")
			(net "FM_9ZXL045_P1_0_OE_N")
		)
		(pad "16" smd rect
			(at 1.75006 2.3749 270)
			(size 0.254 0.5588)
			(layers "F.Cu" "F.Mask" "F.Paste")
			(net "P3V3_9ZXL045_P1_VDD")
		)
		(pad "17" smd rect
			(at 2.3749 1.75006)
			(size 0.254 0.5588)
			(layers "F.Cu" "F.Mask" "F.Paste")
			(net "NC_U10_NC2")
		)
		(pad "18" smd rect
			(at 2.3749 1.249934)
			(size 0.254 0.5588)
			(layers "F.Cu" "F.Mask" "F.Paste")
			(net "FM_9ZXL045_P1_1_OE_N")
		)
		(pad "19" smd rect
			(at 2.3749 0.750062)
			(size 0.254 0.5588)
			(layers "F.Cu" "F.Mask" "F.Paste")
			(net "CLK_100M_RETIMER_CPU1_P1_R_DP")
		)
		(pad "20" smd rect
			(at 2.3749 0.249936)
			(size 0.254 0.5588)
			(layers "F.Cu" "F.Mask" "F.Paste")
			(net "CLK_100M_RETIMER_CPU1_P1_R_DN")
		)
		(pad "21" smd rect
			(at 2.3749 -0.249936)
			(size 0.254 0.5588)
			(layers "F.Cu" "F.Mask" "F.Paste")
			(net "P3V3_9ZXL045_P1_VDD")
		)
		(pad "22" smd rect
			(at 2.3749 -0.750062)
			(size 0.254 0.5588)
			(layers "F.Cu" "F.Mask" "F.Paste")
			(net "CLK_100M_RETIMER_CPU1_P2_R_DP")
		)
		(pad "23" smd rect
			(at 2.3749 -1.249934)
			(size 0.254 0.5588)
			(layers "F.Cu" "F.Mask" "F.Paste")
			(net "CLK_100M_RETIMER_CPU1_P2_R_DN")
		)
		(pad "24" smd rect
			(at 2.3749 -1.75006)
			(size 0.254 0.5588)
			(layers "F.Cu" "F.Mask" "F.Paste")
			(net "FM_9ZXL045_P1_2_OE_N")
		)
		(pad "25" smd rect
			(at 1.75006 -2.3749 90)
			(size 0.254 0.5588)
			(layers "F.Cu" "F.Mask" "F.Paste")
			(net "P3V3_9ZXL045_P1_VDD")
		)
		(pad "26" smd rect
			(at 1.249934 -2.3749 90)
			(size 0.254 0.5588)
			(layers "F.Cu" "F.Mask" "F.Paste")
			(net "FM_9ZXL045_P1_3_OE_N")
		)
		(pad "27" smd rect
			(at 0.750062 -2.3749 90)
			(size 0.254 0.5588)
			(layers "F.Cu" "F.Mask" "F.Paste")
			(net "CLK_100M_RETIMER_CPU1_P3_R_DP")
		)
		(pad "28" smd rect
			(at 0.249936 -2.3749 90)
			(size 0.254 0.5588)
			(layers "F.Cu" "F.Mask" "F.Paste")
			(net "CLK_100M_RETIMER_CPU1_P3_R_DN")
		)
		(pad "29" smd rect
			(at -0.249936 -2.3749 90)
			(size 0.254 0.5588)
			(layers "F.Cu" "F.Mask" "F.Paste")
			(net "P3V3_9ZXL045_P1_VDD")
		)
		(pad "30" smd rect
			(at -0.750062 -2.3749 90)
			(size 0.254 0.5588)
			(layers "F.Cu" "F.Mask" "F.Paste")
			(net "NC_U10_NC3")
		)
		(pad "31" smd rect
			(at -1.249934 -2.3749 90)
			(size 0.254 0.5588)
			(layers "F.Cu" "F.Mask" "F.Paste")
			(net "P3V3_9ZXL045_P1_VDDA")
		)
		(pad "32" smd rect
			(at -1.75006 -2.3749 90)
			(size 0.254 0.5588)
			(layers "F.Cu" "F.Mask" "F.Paste")
			(net "CLK_9ZXL045_P1_HIBW")
		)
		(pad "33" smd rect
			(at 0 0 270)
			(size 3.1496 3.1496)
			(layers "F.Cu" "F.Mask" "F.Paste")
			(net "GND")
		)
	)
)
